(kicad_pcb
	(version 20260206)
	(generator "pcbnew")
	(generator_version "10.0")
	(general
		(thickness 1.6)
		(legacy_teardrops no)
	)
	(paper "A4")
	(title_block
		(title "04192023_DAF0TMB3IC0_F0TG_MB_C_brd_V02_OCP.brd")
		(comment 1 "Grand Teton / footprints 275-280 of 8354")
	)
	(layers
		(0 "F.Cu" signal "TOP")
		(4 "In1.Cu" signal "GND")
		(6 "In2.Cu" signal "IN1")
		(8 "In3.Cu" signal "GND1")
		(10 "In4.Cu" signal "IN2")
		(12 "In5.Cu" signal "GND2")
		(14 "In6.Cu" signal "IN3")
		(16 "In7.Cu" signal "GND3")
		(18 "In8.Cu" signal "VCC")
		(20 "In9.Cu" signal "VCC1")
		(22 "In10.Cu" signal "GND4")
		(24 "In11.Cu" signal "IN4")
		(26 "In12.Cu" signal "GND5")
		(28 "In13.Cu" signal "IN5")
		(30 "In14.Cu" signal "GND6")
		(32 "In15.Cu" signal "IN6")
		(34 "In16.Cu" signal "GND7")
		(2 "B.Cu" signal "BOTTOM")
		(9 "F.Adhes" user "F.Adhesive")
		(11 "B.Adhes" user "B.Adhesive")
		(13 "F.Paste" user "Package Geometry/Pastemask Top")
		(15 "B.Paste" user "Package Geometry/Pastemask Bottom")
		(5 "F.SilkS" user "Ref Des/Silkscreen Top")
		(7 "B.SilkS" user "Ref Des/Silkscreen Bottom")
		(1 "F.Mask" user "Board Geometry/Soldermask Top")
		(3 "B.Mask" user "Board Geometry/Soldermask Bottom")
		(17 "Dwgs.User" user "User.Drawings")
		(19 "Cmts.User" user "User.Comments")
		(21 "Eco1.User" user "User.Eco1")
		(23 "Eco2.User" user "User.Eco2")
		(25 "Edge.Cuts" user "Board Geometry/Outline")
		(27 "Margin" user)
		(31 "F.CrtYd" user "Package Geometry/Place Bound Top")
		(29 "B.CrtYd" user "Package Geometry/Place Bound Bottom")
		(35 "F.Fab" user "Ref Des/Assembly Top")
		(33 "B.Fab" user "Ref Des/Assembly Bottom")
	)
	(footprint ""
		(layer "F.Cu")
		(at 355.506782 -412.030418 180)
		(property "Reference" "R4154"
			(at 0 0 180)
			(layer "F.SilkS")
			(hide yes)
			(effects
				(font
					(size 1.27 1.27)
				)
			)
		)
		(property "Value" ""
			(at 0 0 180)
			(layer "F.Fab")
			(effects
				(font
					(size 1.27 1.27)
				)
			)
		)
		(duplicate_pad_numbers_are_jumpers no)
		(fp_line
			(start 0.7874 0.4064)
			(end -0.7874 0.4064)
			(stroke
				(width 0.1524)
				(type default)
			)
			(layer "F.SilkS")
		)
		(fp_line
			(start 0.7874 -0.4064)
			(end 0.7874 0.4064)
			(stroke
				(width 0.1524)
				(type default)
			)
			(layer "F.SilkS")
		)
		(fp_line
			(start -0.7874 0.4064)
			(end -0.7874 -0.4064)
			(stroke
				(width 0.1524)
				(type default)
			)
			(layer "F.SilkS")
		)
		(fp_line
			(start -0.7874 -0.4064)
			(end 0.7874 -0.4064)
			(stroke
				(width 0.1524)
				(type default)
			)
			(layer "F.SilkS")
		)
		(fp_line
			(start 0.67945 0.3048)
			(end 0.120396 0.3048)
			(stroke
				(width 0.1)
				(type default)
			)
			(layer "F.Fab")
		)
		(fp_line
			(start 0.67945 -0.3048)
			(end 0.67945 0.3048)
			(stroke
				(width 0.1)
				(type default)
			)
			(layer "F.Fab")
		)
		(fp_line
			(start 0.12065 -0.2794)
			(end 0.12065 -0.3048)
			(stroke
				(width 0.1)
				(type default)
			)
			(layer "F.Fab")
		)
		(fp_line
			(start 0.12065 -0.3048)
			(end 0.67945 -0.3048)
			(stroke
				(width 0.1)
				(type default)
			)
			(layer "F.Fab")
		)
		(fp_line
			(start 0.120396 0.3048)
			(end 0.120396 0.2794)
			(stroke
				(width 0.1)
				(type default)
			)
			(layer "F.Fab")
		)
		(fp_line
			(start 0.120396 0.2794)
			(end -0.12065 0.2794)
			(stroke
				(width 0.1)
				(type default)
			)
			(layer "F.Fab")
		)
		(fp_line
			(start -0.12065 0.3048)
			(end -0.67945 0.3048)
			(stroke
				(width 0.1)
				(type default)
			)
			(layer "F.Fab")
		)
		(fp_line
			(start -0.12065 0.2794)
			(end -0.12065 0.3048)
			(stroke
				(width 0.1)
				(type default)
			)
			(layer "F.Fab")
		)
		(fp_line
			(start -0.12065 -0.2794)
			(end 0.12065 -0.2794)
			(stroke
				(width 0.1)
				(type default)
			)
			(layer "F.Fab")
		)
		(fp_line
			(start -0.12065 -0.305054)
			(end -0.12065 -0.2794)
			(stroke
				(width 0.1)
				(type default)
			)
			(layer "F.Fab")
		)
		(fp_line
			(start -0.67945 0.3048)
			(end -0.67945 -0.305054)
			(stroke
				(width 0.1)
				(type default)
			)
			(layer "F.Fab")
		)
		(fp_line
			(start -0.67945 -0.305054)
			(end -0.12065 -0.305054)
			(stroke
				(width 0.1)
				(type default)
			)
			(layer "F.Fab")
		)
		(pad "1" smd circle
			(at -0.40005 0 180)
			(size 0 0)
			(layers "F.Cu" "F.Mask" "F.Paste")
			(net "PRSNT_CABLE_GPU_A1_N")
		)
		(pad "2" smd circle
			(at 0.40005 0 180)
			(size 0 0)
			(layers "F.Cu" "F.Mask" "F.Paste")
			(net "GND")
		)
	)
	(footprint ""
		(layer "F.Cu")
		(at 181.615334 -356.507034 180)
		(property "Reference" "PR328"
			(at 0 0 180)
			(layer "F.SilkS")
			(hide yes)
			(effects
				(font
					(size 1.27 1.27)
				)
			)
		)
		(property "Value" ""
			(at 0 0 180)
			(layer "F.Fab")
			(effects
				(font
					(size 1.27 1.27)
				)
			)
		)
		(duplicate_pad_numbers_are_jumpers no)
		(fp_line
			(start 0.7874 0.4064)
			(end -0.7874 0.4064)
			(stroke
				(width 0.1524)
				(type default)
			)
			(layer "F.SilkS")
		)
		(fp_line
			(start 0.7874 -0.4064)
			(end 0.7874 0.4064)
			(stroke
				(width 0.1524)
				(type default)
			)
			(layer "F.SilkS")
		)
		(fp_line
			(start -0.7874 0.4064)
			(end -0.7874 -0.4064)
			(stroke
				(width 0.1524)
				(type default)
			)
			(layer "F.SilkS")
		)
		(fp_line
			(start -0.7874 -0.4064)
			(end 0.7874 -0.4064)
			(stroke
				(width 0.1524)
				(type default)
			)
			(layer "F.SilkS")
		)
		(fp_line
			(start 0.67945 0.3048)
			(end 0.120396 0.3048)
			(stroke
				(width 0.1)
				(type default)
			)
			(layer "F.Fab")
		)
		(fp_line
			(start 0.67945 -0.3048)
			(end 0.67945 0.3048)
			(stroke
				(width 0.1)
				(type default)
			)
			(layer "F.Fab")
		)
		(fp_line
			(start 0.12065 -0.2794)
			(end 0.12065 -0.3048)
			(stroke
				(width 0.1)
				(type default)
			)
			(layer "F.Fab")
		)
		(fp_line
			(start 0.12065 -0.3048)
			(end 0.67945 -0.3048)
			(stroke
				(width 0.1)
				(type default)
			)
			(layer "F.Fab")
		)
		(fp_line
			(start 0.120396 0.3048)
			(end 0.120396 0.2794)
			(stroke
				(width 0.1)
				(type default)
			)
			(layer "F.Fab")
		)
		(fp_line
			(start 0.120396 0.2794)
			(end -0.12065 0.2794)
			(stroke
				(width 0.1)
				(type default)
			)
			(layer "F.Fab")
		)
		(fp_line
			(start -0.12065 0.3048)
			(end -0.67945 0.3048)
			(stroke
				(width 0.1)
				(type default)
			)
			(layer "F.Fab")
		)
		(fp_line
			(start -0.12065 0.2794)
			(end -0.12065 0.3048)
			(stroke
				(width 0.1)
				(type default)
			)
			(layer "F.Fab")
		)
		(fp_line
			(start -0.12065 -0.2794)
			(end 0.12065 -0.2794)
			(stroke
				(width 0.1)
				(type default)
			)
			(layer "F.Fab")
		)
		(fp_line
			(start -0.12065 -0.305054)
			(end -0.12065 -0.2794)
			(stroke
				(width 0.1)
				(type default)
			)
			(layer "F.Fab")
		)
		(fp_line
			(start -0.67945 0.3048)
			(end -0.67945 -0.305054)
			(stroke
				(width 0.1)
				(type default)
			)
			(layer "F.Fab")
		)
		(fp_line
			(start -0.67945 -0.305054)
			(end -0.12065 -0.305054)
			(stroke
				(width 0.1)
				(type default)
			)
			(layer "F.Fab")
		)
		(pad "1" smd circle
			(at -0.40005 0 180)
			(size 0 0)
			(layers "F.Cu" "F.Mask" "F.Paste")
			(net "GND")
		)
		(pad "2" smd circle
			(at 0.40005 0 180)
			(size 0 0)
			(layers "F.Cu" "F.Mask" "F.Paste")
			(net "PVDD11_S3_P1_LSET1")
		)
	)
	(footprint ""
		(layer "F.Cu")
		(at 275.14169 -96.323404 180)
		(property "Reference" "R1642"
			(at 0 0 180)
			(layer "F.SilkS")
			(hide yes)
			(effects
				(font
					(size 1.27 1.27)
				)
			)
		)
		(property "Value" ""
			(at 0 0 180)
			(layer "F.Fab")
			(effects
				(font
					(size 1.27 1.27)
				)
			)
		)
		(duplicate_pad_numbers_are_jumpers no)
		(fp_line
			(start 0.7874 0.4064)
			(end -0.7874 0.4064)
			(stroke
				(width 0.1524)
				(type default)
			)
			(layer "F.SilkS")
		)
		(fp_line
			(start 0.7874 -0.4064)
			(end 0.7874 0.4064)
			(stroke
				(width 0.1524)
				(type default)
			)
			(layer "F.SilkS")
		)
		(fp_line
			(start -0.7874 0.4064)
			(end -0.7874 -0.4064)
			(stroke
				(width 0.1524)
				(type default)
			)
			(layer "F.SilkS")
		)
		(fp_line
			(start -0.7874 -0.4064)
			(end 0.7874 -0.4064)
			(stroke
				(width 0.1524)
				(type default)
			)
			(layer "F.SilkS")
		)
		(fp_line
			(start 0.67945 0.3048)
			(end 0.120396 0.3048)
			(stroke
				(width 0.1)
				(type default)
			)
			(layer "F.Fab")
		)
		(fp_line
			(start 0.67945 -0.3048)
			(end 0.67945 0.3048)
			(stroke
				(width 0.1)
				(type default)
			)
			(layer "F.Fab")
		)
		(fp_line
			(start 0.12065 -0.2794)
			(end 0.12065 -0.3048)
			(stroke
				(width 0.1)
				(type default)
			)
			(layer "F.Fab")
		)
		(fp_line
			(start 0.12065 -0.3048)
			(end 0.67945 -0.3048)
			(stroke
				(width 0.1)
				(type default)
			)
			(layer "F.Fab")
		)
		(fp_line
			(start 0.120396 0.3048)
			(end 0.120396 0.2794)
			(stroke
				(width 0.1)
				(type default)
			)
			(layer "F.Fab")
		)
		(fp_line
			(start 0.120396 0.2794)
			(end -0.12065 0.2794)
			(stroke
				(width 0.1)
				(type default)
			)
			(layer "F.Fab")
		)
		(fp_line
			(start -0.12065 0.3048)
			(end -0.67945 0.3048)
			(stroke
				(width 0.1)
				(type default)
			)
			(layer "F.Fab")
		)
		(fp_line
			(start -0.12065 0.2794)
			(end -0.12065 0.3048)
			(stroke
				(width 0.1)
				(type default)
			)
			(layer "F.Fab")
		)
		(fp_line
			(start -0.12065 -0.2794)
			(end 0.12065 -0.2794)
			(stroke
				(width 0.1)
				(type default)
			)
			(layer "F.Fab")
		)
		(fp_line
			(start -0.12065 -0.305054)
			(end -0.12065 -0.2794)
			(stroke
				(width 0.1)
				(type default)
			)
			(layer "F.Fab")
		)
		(fp_line
			(start -0.67945 0.3048)
			(end -0.67945 -0.305054)
			(stroke
				(width 0.1)
				(type default)
			)
			(layer "F.Fab")
		)
		(fp_line
			(start -0.67945 -0.305054)
			(end -0.12065 -0.305054)
			(stroke
				(width 0.1)
				(type default)
			)
			(layer "F.Fab")
		)
		(pad "1" smd circle
			(at -0.40005 0 180)
			(size 0 0)
			(layers "F.Cu" "F.Mask" "F.Paste")
			(net "JTAG_P1_R_TCK")
		)
		(pad "2" smd circle
			(at 0.40005 0 180)
			(size 0 0)
			(layers "F.Cu" "F.Mask" "F.Paste")
			(net "JTAG_CPU1_TCK")
		)
	)
	(footprint ""
		(layer "F.Cu")
		(at 192.599564 -67.391788 180)
		(property "Reference" "PR3945"
			(at 0 0 180)
			(layer "F.SilkS")
			(hide yes)
			(effects
				(font
					(size 1.27 1.27)
				)
			)
		)
		(property "Value" ""
			(at 0 0 180)
			(layer "F.Fab")
			(effects
				(font
					(size 1.27 1.27)
				)
			)
		)
		(duplicate_pad_numbers_are_jumpers no)
		(fp_line
			(start 0.7874 0.4064)
			(end -0.7874 0.4064)
			(stroke
				(width 0.1524)
				(type default)
			)
			(layer "F.SilkS")
		)
		(fp_line
			(start 0.7874 -0.4064)
			(end 0.7874 0.4064)
			(stroke
				(width 0.1524)
				(type default)
			)
			(layer "F.SilkS")
		)
		(fp_line
			(start -0.7874 0.4064)
			(end -0.7874 -0.4064)
			(stroke
				(width 0.1524)
				(type default)
			)
			(layer "F.SilkS")
		)
		(fp_line
			(start -0.7874 -0.4064)
			(end 0.7874 -0.4064)
			(stroke
				(width 0.1524)
				(type default)
			)
			(layer "F.SilkS")
		)
		(fp_line
			(start 0.67945 0.3048)
			(end 0.120396 0.3048)
			(stroke
				(width 0.1)
				(type default)
			)
			(layer "F.Fab")
		)
		(fp_line
			(start 0.67945 -0.3048)
			(end 0.67945 0.3048)
			(stroke
				(width 0.1)
				(type default)
			)
			(layer "F.Fab")
		)
		(fp_line
			(start 0.12065 -0.2794)
			(end 0.12065 -0.3048)
			(stroke
				(width 0.1)
				(type default)
			)
			(layer "F.Fab")
		)
		(fp_line
			(start 0.12065 -0.3048)
			(end 0.67945 -0.3048)
			(stroke
				(width 0.1)
				(type default)
			)
			(layer "F.Fab")
		)
		(fp_line
			(start 0.120396 0.3048)
			(end 0.120396 0.2794)
			(stroke
				(width 0.1)
				(type default)
			)
			(layer "F.Fab")
		)
		(fp_line
			(start 0.120396 0.2794)
			(end -0.12065 0.2794)
			(stroke
				(width 0.1)
				(type default)
			)
			(layer "F.Fab")
		)
		(fp_line
			(start -0.12065 0.3048)
			(end -0.67945 0.3048)
			(stroke
				(width 0.1)
				(type default)
			)
			(layer "F.Fab")
		)
		(fp_line
			(start -0.12065 0.2794)
			(end -0.12065 0.3048)
			(stroke
				(width 0.1)
				(type default)
			)
			(layer "F.Fab")
		)
		(fp_line
			(start -0.12065 -0.2794)
			(end 0.12065 -0.2794)
			(stroke
				(width 0.1)
				(type default)
			)
			(layer "F.Fab")
		)
		(fp_line
			(start -0.12065 -0.305054)
			(end -0.12065 -0.2794)
			(stroke
				(width 0.1)
				(type default)
			)
			(layer "F.Fab")
		)
		(fp_line
			(start -0.67945 0.3048)
			(end -0.67945 -0.305054)
			(stroke
				(width 0.1)
				(type default)
			)
			(layer "F.Fab")
		)
		(fp_line
			(start -0.67945 -0.305054)
			(end -0.12065 -0.305054)
			(stroke
				(width 0.1)
				(type default)
			)
			(layer "F.Fab")
		)
		(pad "1" smd circle
			(at -0.40005 0 180)
			(size 0 0)
			(layers "F.Cu" "F.Mask" "F.Paste")
			(net "P3V3_E1S_MODE_0")
		)
		(pad "2" smd circle
			(at 0.40005 0 180)
			(size 0 0)
			(layers "F.Cu" "F.Mask" "F.Paste")
			(net "GND")
		)
	)
	(footprint ""
		(layer "F.Cu")
		(at 455.228452 -15.503398 180)
		(property "Reference" "PD102"
			(at -3.501136 -2.022348 0)
			(unlocked yes)
			(layer "F.SilkS")
			(effects
				(font
					(size 0.7874 0.5842)
					(thickness 0.1524)
				)
				(justify left)
			)
		)
		(property "Value" ""
			(at 0 0 180)
			(layer "F.Fab")
			(effects
				(font
					(size 1.27 1.27)
				)
			)
		)
		(duplicate_pad_numbers_are_jumpers no)
		(fp_line
			(start 4.107942 1.459992)
			(end -3.400044 1.459992)
			(stroke
				(width 0.1524)
				(type default)
			)
			(layer "F.SilkS")
		)
		(fp_line
			(start 4.107942 -1.459992)
			(end 4.107942 1.459992)
			(stroke
				(width 0.1524)
				(type default)
			)
			(layer "F.SilkS")
		)
		(fp_line
			(start -3.400044 1.459992)
			(end -3.400044 -1.459992)
			(stroke
				(width 0.1524)
				(type default)
			)
			(layer "F.SilkS")
		)
		(fp_line
			(start -3.400044 -1.459992)
			(end 4.107942 -1.459992)
			(stroke
				(width 0.1524)
				(type default)
			)
			(layer "F.SilkS")
		)
		(fp_rect
			(start 4.107942 -1.459992)
			(end 3.308096 1.459992)
			(stroke
				(width 0)
				(type default)
			)
			(fill yes)
			(layer "F.SilkS")
		)
		(fp_line
			(start 2.29997 1.459992)
			(end -2.29997 1.459992)
			(stroke
				(width 0.1)
				(type default)
			)
			(layer "F.Fab")
		)
		(fp_line
			(start 2.29997 -1.459992)
			(end 2.29997 1.459992)
			(stroke
				(width 0.1)
				(type default)
			)
			(layer "F.Fab")
		)
		(fp_line
			(start -2.29997 1.459992)
			(end -2.29997 -1.459992)
			(stroke
				(width 0.1)
				(type default)
			)
			(layer "F.Fab")
		)
		(fp_line
			(start -2.29997 -1.459992)
			(end 2.29997 -1.459992)
			(stroke
				(width 0.1)
				(type default)
			)
			(layer "F.Fab")
		)
		(fp_text user "-"
			(at 5.4102 0.29845 0)
			(unlocked yes)
			(layer "F.SilkS")
			(effects
				(font
					(size 1.905 1.4224)
					(thickness 0.1524)
				)
				(justify left)
			)
		)
		(fp_text user "+"
			(at -5.083302 0.161036 180)
			(unlocked yes)
			(layer "F.SilkS")
			(effects
				(font
					(size 1.905 1.4224)
					(thickness 0.1524)
				)
				(justify left)
			)
		)
		(fp_text user "-"
			(at 5.4102 0.29845 0)
			(unlocked yes)
			(layer "F.Fab")
			(effects
				(font
					(size 1.905 1.4224)
					(thickness 0.1524)
				)
				(justify left)
			)
		)
		(fp_text user "+"
			(at -4.7752 -0.12065 180)
			(unlocked yes)
			(layer "F.Fab")
			(effects
				(font
					(size 1.905 1.4224)
					(thickness 0.1524)
				)
				(justify left)
			)
		)
		(pad "A" smd rect
			(at -1.999996 0 270)
			(size 1.7018 2.5146)
			(layers "F.Cu" "F.Mask" "F.Paste")
			(net "GND")
		)
		(pad "C" smd rect
			(at 1.999996 0 270)
			(size 1.7018 2.5146)
			(layers "F.Cu" "F.Mask" "F.Paste")
			(net "P12V_OCP_SFF")
		)
	)
	(footprint ""
		(layer "F.Cu")
		(at 31.331662 -429.759364 -90)
		(property "Reference" "R3280"
			(at 0 0 270)
			(layer "F.SilkS")
			(hide yes)
			(effects
				(font
					(size 1.27 1.27)
				)
			)
		)
		(property "Value" ""
			(at 0 0 270)
			(layer "F.Fab")
			(effects
				(font
					(size 1.27 1.27)
				)
			)
		)
		(duplicate_pad_numbers_are_jumpers no)
		(fp_line
			(start -0.7874 0.4064)
			(end -0.7874 -0.4064)
			(stroke
				(width 0.1524)
				(type default)
			)
			(layer "F.SilkS")
		)
		(fp_line
			(start 0.7874 0.4064)
			(end -0.7874 0.4064)
			(stroke
				(width 0.1524)
				(type default)
			)
			(layer "F.SilkS")
		)
		(fp_line
			(start -0.7874 -0.4064)
			(end 0.7874 -0.4064)
			(stroke
				(width 0.1524)
				(type default)
			)
			(layer "F.SilkS")
		)
		(fp_line
			(start 0.7874 -0.4064)
			(end 0.7874 0.4064)
			(stroke
				(width 0.1524)
				(type default)
			)
			(layer "F.SilkS")
		)
		(fp_line
			(start -0.67945 0.3048)
			(end -0.67945 -0.305054)
			(stroke
				(width 0.1)
				(type default)
			)
			(layer "F.Fab")
		)
		(fp_line
			(start -0.12065 0.3048)
			(end -0.67945 0.3048)
			(stroke
				(width 0.1)
				(type default)
			)
			(layer "F.Fab")
		)
		(fp_line
			(start 0.120396 0.3048)
			(end 0.120396 0.2794)
			(stroke
				(width 0.1)
				(type default)
			)
			(layer "F.Fab")
		)
		(fp_line
			(start 0.67945 0.3048)
			(end 0.120396 0.3048)
			(stroke
				(width 0.1)
				(type default)
			)
			(layer "F.Fab")
		)
		(fp_line
			(start -0.12065 0.2794)
			(end -0.12065 0.3048)
			(stroke
				(width 0.1)
				(type default)
			)
			(layer "F.Fab")
		)
		(fp_line
			(start 0.120396 0.2794)
			(end -0.12065 0.2794)
			(stroke
				(width 0.1)
				(type default)
			)
			(layer "F.Fab")
		)
		(fp_line
			(start -0.12065 -0.2794)
			(end 0.12065 -0.2794)
			(stroke
				(width 0.1)
				(type default)
			)
			(layer "F.Fab")
		)
		(fp_line
			(start 0.12065 -0.2794)
			(end 0.12065 -0.3048)
			(stroke
				(width 0.1)
				(type default)
			)
			(layer "F.Fab")
		)
		(fp_line
			(start 0.12065 -0.3048)
			(end 0.67945 -0.3048)
			(stroke
				(width 0.1)
				(type default)
			)
			(layer "F.Fab")
		)
		(fp_line
			(start 0.67945 -0.3048)
			(end 0.67945 0.3048)
			(stroke
				(width 0.1)
				(type default)
			)
			(layer "F.Fab")
		)
		(fp_line
			(start -0.67945 -0.305054)
			(end -0.12065 -0.305054)
			(stroke
				(width 0.1)
				(type default)
			)
			(layer "F.Fab")
		)
		(fp_line
			(start -0.12065 -0.305054)
			(end -0.12065 -0.2794)
			(stroke
				(width 0.1)
				(type default)
			)
			(layer "F.Fab")
		)
		(pad "1" smd circle
			(at -0.40005 0 270)
			(size 0 0)
			(layers "F.Cu" "F.Mask" "F.Paste")
			(net "P3V3_AUX")
		)
		(pad "2" smd circle
			(at 0.40005 0 270)
			(size 0 0)
			(layers "F.Cu" "F.Mask" "F.Paste")
			(net "FM_P2E_EQB1")
		)
	)
)
